(kicad_pcb
	(version 20260206)
	(generator "pcbnew")
	(generator_version "10.0")
	(general
		(thickness 1.6)
		(legacy_teardrops no)
	)
	(paper "A4")
	(title_block
		(title "04192023_DAF0TMB3IC0_F0TG_MB_C_brd_V02_OCP.brd")
		(comment 1 "Grand Teton / footprints 3838-3844 of 8354")
	)
	(layers
		(0 "F.Cu" signal "TOP")
		(4 "In1.Cu" signal "GND")
		(6 "In2.Cu" signal "IN1")
		(8 "In3.Cu" signal "GND1")
		(10 "In4.Cu" signal "IN2")
		(12 "In5.Cu" signal "GND2")
		(14 "In6.Cu" signal "IN3")
		(16 "In7.Cu" signal "GND3")
		(18 "In8.Cu" signal "VCC")
		(20 "In9.Cu" signal "VCC1")
		(22 "In10.Cu" signal "GND4")
		(24 "In11.Cu" signal "IN4")
		(26 "In12.Cu" signal "GND5")
		(28 "In13.Cu" signal "IN5")
		(30 "In14.Cu" signal "GND6")
		(32 "In15.Cu" signal "IN6")
		(34 "In16.Cu" signal "GND7")
		(2 "B.Cu" signal "BOTTOM")
		(9 "F.Adhes" user "F.Adhesive")
		(11 "B.Adhes" user "B.Adhesive")
		(13 "F.Paste" user "Package Geometry/Pastemask Top")
		(15 "B.Paste" user "Package Geometry/Pastemask Bottom")
		(5 "F.SilkS" user "Ref Des/Silkscreen Top")
		(7 "B.SilkS" user "Ref Des/Silkscreen Bottom")
		(1 "F.Mask" user "Board Geometry/Soldermask Top")
		(3 "B.Mask" user "Board Geometry/Soldermask Bottom")
		(17 "Dwgs.User" user "User.Drawings")
		(19 "Cmts.User" user "User.Comments")
		(21 "Eco1.User" user "User.Eco1")
		(23 "Eco2.User" user "User.Eco2")
		(25 "Edge.Cuts" user "Board Geometry/Outline")
		(27 "Margin" user)
		(31 "F.CrtYd" user "Package Geometry/Place Bound Top")
		(29 "B.CrtYd" user "Package Geometry/Place Bound Bottom")
		(35 "F.Fab" user "Ref Des/Assembly Top")
		(33 "B.Fab" user "Ref Des/Assembly Bottom")
	)
	(footprint ""
		(layer "F.Cu")
		(at 90.209878 -147.93341 180)
		(property "Reference" "R8160"
			(at 0 0 180)
			(layer "F.SilkS")
			(hide yes)
			(effects
				(font
					(size 1.27 1.27)
				)
			)
		)
		(property "Value" ""
			(at 0 0 180)
			(layer "F.Fab")
			(effects
				(font
					(size 1.27 1.27)
				)
			)
		)
		(duplicate_pad_numbers_are_jumpers no)
		(fp_line
			(start 0.7874 0.4064)
			(end -0.7874 0.4064)
			(stroke
				(width 0.1524)
				(type default)
			)
			(layer "F.SilkS")
		)
		(fp_line
			(start 0.7874 -0.4064)
			(end 0.7874 0.4064)
			(stroke
				(width 0.1524)
				(type default)
			)
			(layer "F.SilkS")
		)
		(fp_line
			(start -0.7874 0.4064)
			(end -0.7874 -0.4064)
			(stroke
				(width 0.1524)
				(type default)
			)
			(layer "F.SilkS")
		)
		(fp_line
			(start -0.7874 -0.4064)
			(end 0.7874 -0.4064)
			(stroke
				(width 0.1524)
				(type default)
			)
			(layer "F.SilkS")
		)
		(fp_line
			(start 0.67945 0.3048)
			(end 0.120396 0.3048)
			(stroke
				(width 0.1)
				(type default)
			)
			(layer "F.Fab")
		)
		(fp_line
			(start 0.67945 -0.3048)
			(end 0.67945 0.3048)
			(stroke
				(width 0.1)
				(type default)
			)
			(layer "F.Fab")
		)
		(fp_line
			(start 0.12065 -0.2794)
			(end 0.12065 -0.3048)
			(stroke
				(width 0.1)
				(type default)
			)
			(layer "F.Fab")
		)
		(fp_line
			(start 0.12065 -0.3048)
			(end 0.67945 -0.3048)
			(stroke
				(width 0.1)
				(type default)
			)
			(layer "F.Fab")
		)
		(fp_line
			(start 0.120396 0.3048)
			(end 0.120396 0.2794)
			(stroke
				(width 0.1)
				(type default)
			)
			(layer "F.Fab")
		)
		(fp_line
			(start 0.120396 0.2794)
			(end -0.12065 0.2794)
			(stroke
				(width 0.1)
				(type default)
			)
			(layer "F.Fab")
		)
		(fp_line
			(start -0.12065 0.3048)
			(end -0.67945 0.3048)
			(stroke
				(width 0.1)
				(type default)
			)
			(layer "F.Fab")
		)
		(fp_line
			(start -0.12065 0.2794)
			(end -0.12065 0.3048)
			(stroke
				(width 0.1)
				(type default)
			)
			(layer "F.Fab")
		)
		(fp_line
			(start -0.12065 -0.2794)
			(end 0.12065 -0.2794)
			(stroke
				(width 0.1)
				(type default)
			)
			(layer "F.Fab")
		)
		(fp_line
			(start -0.12065 -0.305054)
			(end -0.12065 -0.2794)
			(stroke
				(width 0.1)
				(type default)
			)
			(layer "F.Fab")
		)
		(fp_line
			(start -0.67945 0.3048)
			(end -0.67945 -0.305054)
			(stroke
				(width 0.1)
				(type default)
			)
			(layer "F.Fab")
		)
		(fp_line
			(start -0.67945 -0.305054)
			(end -0.12065 -0.305054)
			(stroke
				(width 0.1)
				(type default)
			)
			(layer "F.Fab")
		)
		(pad "1" smd circle
			(at -0.40005 0 180)
			(size 0 0)
			(layers "F.Cu" "F.Mask" "F.Paste")
			(net "PVDD18_S5_P1")
		)
		(pad "2" smd circle
			(at 0.40005 0 180)
			(size 0 0)
			(layers "F.Cu" "F.Mask" "F.Paste")
			(net "SVID_PVDDCR_CPU0_P1_SVC_R")
		)
	)
	(footprint ""
		(layer "F.Cu")
		(at 101.767894 -177.83556 -90)
		(property "Reference" "PC284_3"
			(at 0 0 270)
			(layer "F.SilkS")
			(hide yes)
			(effects
				(font
					(size 1.27 1.27)
				)
			)
		)
		(property "Value" ""
			(at 0 0 270)
			(layer "F.Fab")
			(effects
				(font
					(size 1.27 1.27)
				)
			)
		)
		(duplicate_pad_numbers_are_jumpers no)
		(fp_line
			(start -0.7874 0.4064)
			(end -0.7874 -0.4064)
			(stroke
				(width 0.1524)
				(type default)
			)
			(layer "F.SilkS")
		)
		(fp_line
			(start 0.7874 0.4064)
			(end -0.7874 0.4064)
			(stroke
				(width 0.1524)
				(type default)
			)
			(layer "F.SilkS")
		)
		(fp_line
			(start -0.7874 -0.4064)
			(end 0.7874 -0.4064)
			(stroke
				(width 0.1524)
				(type default)
			)
			(layer "F.SilkS")
		)
		(fp_line
			(start 0.7874 -0.4064)
			(end 0.7874 0.4064)
			(stroke
				(width 0.1524)
				(type default)
			)
			(layer "F.SilkS")
		)
		(fp_line
			(start -0.67945 0.3048)
			(end -0.67945 -0.305054)
			(stroke
				(width 0.1)
				(type default)
			)
			(layer "F.Fab")
		)
		(fp_line
			(start -0.12065 0.3048)
			(end -0.67945 0.3048)
			(stroke
				(width 0.1)
				(type default)
			)
			(layer "F.Fab")
		)
		(fp_line
			(start 0.120396 0.3048)
			(end 0.120396 0.2794)
			(stroke
				(width 0.1)
				(type default)
			)
			(layer "F.Fab")
		)
		(fp_line
			(start 0.67945 0.3048)
			(end 0.120396 0.3048)
			(stroke
				(width 0.1)
				(type default)
			)
			(layer "F.Fab")
		)
		(fp_line
			(start -0.12065 0.2794)
			(end -0.12065 0.3048)
			(stroke
				(width 0.1)
				(type default)
			)
			(layer "F.Fab")
		)
		(fp_line
			(start 0.120396 0.2794)
			(end -0.12065 0.2794)
			(stroke
				(width 0.1)
				(type default)
			)
			(layer "F.Fab")
		)
		(fp_line
			(start -0.12065 -0.2794)
			(end 0.12065 -0.2794)
			(stroke
				(width 0.1)
				(type default)
			)
			(layer "F.Fab")
		)
		(fp_line
			(start 0.12065 -0.2794)
			(end 0.12065 -0.3048)
			(stroke
				(width 0.1)
				(type default)
			)
			(layer "F.Fab")
		)
		(fp_line
			(start 0.12065 -0.3048)
			(end 0.67945 -0.3048)
			(stroke
				(width 0.1)
				(type default)
			)
			(layer "F.Fab")
		)
		(fp_line
			(start 0.67945 -0.3048)
			(end 0.67945 0.3048)
			(stroke
				(width 0.1)
				(type default)
			)
			(layer "F.Fab")
		)
		(fp_line
			(start -0.67945 -0.305054)
			(end -0.12065 -0.305054)
			(stroke
				(width 0.1)
				(type default)
			)
			(layer "F.Fab")
		)
		(fp_line
			(start -0.12065 -0.305054)
			(end -0.12065 -0.2794)
			(stroke
				(width 0.1)
				(type default)
			)
			(layer "F.Fab")
		)
		(pad "1" smd circle
			(at -0.40005 0 270)
			(size 0 0)
			(layers "F.Cu" "F.Mask" "F.Paste")
			(net "PVDDCR_CPU0_P1_VCCS")
		)
		(pad "2" smd circle
			(at 0.40005 0 270)
			(size 0 0)
			(layers "F.Cu" "F.Mask" "F.Paste")
			(net "GND")
		)
	)
	(footprint ""
		(layer "F.Cu")
		(at 137.971784 -50.611024 180)
		(property "Reference" "R6215"
			(at 0 0 180)
			(layer "F.SilkS")
			(hide yes)
			(effects
				(font
					(size 1.27 1.27)
				)
			)
		)
		(property "Value" ""
			(at 0 0 180)
			(layer "F.Fab")
			(effects
				(font
					(size 1.27 1.27)
				)
			)
		)
		(duplicate_pad_numbers_are_jumpers no)
		(fp_line
			(start 0.7874 0.4064)
			(end -0.7874 0.4064)
			(stroke
				(width 0.1524)
				(type default)
			)
			(layer "F.SilkS")
		)
		(fp_line
			(start 0.7874 -0.4064)
			(end 0.7874 0.4064)
			(stroke
				(width 0.1524)
				(type default)
			)
			(layer "F.SilkS")
		)
		(fp_line
			(start -0.7874 0.4064)
			(end -0.7874 -0.4064)
			(stroke
				(width 0.1524)
				(type default)
			)
			(layer "F.SilkS")
		)
		(fp_line
			(start -0.7874 -0.4064)
			(end 0.7874 -0.4064)
			(stroke
				(width 0.1524)
				(type default)
			)
			(layer "F.SilkS")
		)
		(fp_line
			(start 0.67945 0.3048)
			(end 0.120396 0.3048)
			(stroke
				(width 0.1)
				(type default)
			)
			(layer "F.Fab")
		)
		(fp_line
			(start 0.67945 -0.3048)
			(end 0.67945 0.3048)
			(stroke
				(width 0.1)
				(type default)
			)
			(layer "F.Fab")
		)
		(fp_line
			(start 0.12065 -0.2794)
			(end 0.12065 -0.3048)
			(stroke
				(width 0.1)
				(type default)
			)
			(layer "F.Fab")
		)
		(fp_line
			(start 0.12065 -0.3048)
			(end 0.67945 -0.3048)
			(stroke
				(width 0.1)
				(type default)
			)
			(layer "F.Fab")
		)
		(fp_line
			(start 0.120396 0.3048)
			(end 0.120396 0.2794)
			(stroke
				(width 0.1)
				(type default)
			)
			(layer "F.Fab")
		)
		(fp_line
			(start 0.120396 0.2794)
			(end -0.12065 0.2794)
			(stroke
				(width 0.1)
				(type default)
			)
			(layer "F.Fab")
		)
		(fp_line
			(start -0.12065 0.3048)
			(end -0.67945 0.3048)
			(stroke
				(width 0.1)
				(type default)
			)
			(layer "F.Fab")
		)
		(fp_line
			(start -0.12065 0.2794)
			(end -0.12065 0.3048)
			(stroke
				(width 0.1)
				(type default)
			)
			(layer "F.Fab")
		)
		(fp_line
			(start -0.12065 -0.2794)
			(end 0.12065 -0.2794)
			(stroke
				(width 0.1)
				(type default)
			)
			(layer "F.Fab")
		)
		(fp_line
			(start -0.12065 -0.305054)
			(end -0.12065 -0.2794)
			(stroke
				(width 0.1)
				(type default)
			)
			(layer "F.Fab")
		)
		(fp_line
			(start -0.67945 0.3048)
			(end -0.67945 -0.305054)
			(stroke
				(width 0.1)
				(type default)
			)
			(layer "F.Fab")
		)
		(fp_line
			(start -0.67945 -0.305054)
			(end -0.12065 -0.305054)
			(stroke
				(width 0.1)
				(type default)
			)
			(layer "F.Fab")
		)
		(pad "1" smd circle
			(at -0.40005 0 180)
			(size 0 0)
			(layers "F.Cu" "F.Mask" "F.Paste")
			(net "P3V3_AUX")
		)
		(pad "2" smd circle
			(at 0.40005 0 180)
			(size 0 0)
			(layers "F.Cu" "F.Mask" "F.Paste")
			(net "USB_CPU0_HUB1_MODE_SEL0")
		)
	)
	(footprint ""
		(layer "F.Cu")
		(at 75.546458 -21.839682 180)
		(property "Reference" "PR3823"
			(at 0 0 180)
			(layer "F.SilkS")
			(hide yes)
			(effects
				(font
					(size 1.27 1.27)
				)
			)
		)
		(property "Value" ""
			(at 0 0 180)
			(layer "F.Fab")
			(effects
				(font
					(size 1.27 1.27)
				)
			)
		)
		(duplicate_pad_numbers_are_jumpers no)
		(fp_line
			(start 0.7874 0.4064)
			(end -0.7874 0.4064)
			(stroke
				(width 0.1524)
				(type default)
			)
			(layer "F.SilkS")
		)
		(fp_line
			(start 0.7874 -0.4064)
			(end 0.7874 0.4064)
			(stroke
				(width 0.1524)
				(type default)
			)
			(layer "F.SilkS")
		)
		(fp_line
			(start -0.7874 0.4064)
			(end -0.7874 -0.4064)
			(stroke
				(width 0.1524)
				(type default)
			)
			(layer "F.SilkS")
		)
		(fp_line
			(start -0.7874 -0.4064)
			(end 0.7874 -0.4064)
			(stroke
				(width 0.1524)
				(type default)
			)
			(layer "F.SilkS")
		)
		(fp_line
			(start 0.67945 0.3048)
			(end 0.120396 0.3048)
			(stroke
				(width 0.1)
				(type default)
			)
			(layer "F.Fab")
		)
		(fp_line
			(start 0.67945 -0.3048)
			(end 0.67945 0.3048)
			(stroke
				(width 0.1)
				(type default)
			)
			(layer "F.Fab")
		)
		(fp_line
			(start 0.12065 -0.2794)
			(end 0.12065 -0.3048)
			(stroke
				(width 0.1)
				(type default)
			)
			(layer "F.Fab")
		)
		(fp_line
			(start 0.12065 -0.3048)
			(end 0.67945 -0.3048)
			(stroke
				(width 0.1)
				(type default)
			)
			(layer "F.Fab")
		)
		(fp_line
			(start 0.120396 0.3048)
			(end 0.120396 0.2794)
			(stroke
				(width 0.1)
				(type default)
			)
			(layer "F.Fab")
		)
		(fp_line
			(start 0.120396 0.2794)
			(end -0.12065 0.2794)
			(stroke
				(width 0.1)
				(type default)
			)
			(layer "F.Fab")
		)
		(fp_line
			(start -0.12065 0.3048)
			(end -0.67945 0.3048)
			(stroke
				(width 0.1)
				(type default)
			)
			(layer "F.Fab")
		)
		(fp_line
			(start -0.12065 0.2794)
			(end -0.12065 0.3048)
			(stroke
				(width 0.1)
				(type default)
			)
			(layer "F.Fab")
		)
		(fp_line
			(start -0.12065 -0.2794)
			(end 0.12065 -0.2794)
			(stroke
				(width 0.1)
				(type default)
			)
			(layer "F.Fab")
		)
		(fp_line
			(start -0.12065 -0.305054)
			(end -0.12065 -0.2794)
			(stroke
				(width 0.1)
				(type default)
			)
			(layer "F.Fab")
		)
		(fp_line
			(start -0.67945 0.3048)
			(end -0.67945 -0.305054)
			(stroke
				(width 0.1)
				(type default)
			)
			(layer "F.Fab")
		)
		(fp_line
			(start -0.67945 -0.305054)
			(end -0.12065 -0.305054)
			(stroke
				(width 0.1)
				(type default)
			)
			(layer "F.Fab")
		)
		(pad "1" smd circle
			(at -0.40005 0 180)
			(size 0 0)
			(layers "F.Cu" "F.Mask" "F.Paste")
			(net "P12V_OCP_SENSE_2")
		)
		(pad "2" smd circle
			(at 0.40005 0 180)
			(size 0 0)
			(layers "F.Cu" "F.Mask" "F.Paste")
			(net "GND")
		)
	)
	(footprint ""
		(layer "F.Cu")
		(at 122.55627 -35.430968)
		(property "Reference" "C6026"
			(at 0 0 0)
			(layer "F.SilkS")
			(hide yes)
			(effects
				(font
					(size 1.27 1.27)
				)
			)
		)
		(property "Value" ""
			(at 0 0 0)
			(layer "F.Fab")
			(effects
				(font
					(size 1.27 1.27)
				)
			)
		)
		(duplicate_pad_numbers_are_jumpers no)
		(fp_line
			(start -0.7874 -0.4064)
			(end 0.7874 -0.4064)
			(stroke
				(width 0.1524)
				(type default)
			)
			(layer "F.SilkS")
		)
		(fp_line
			(start -0.7874 0.4064)
			(end -0.7874 -0.4064)
			(stroke
				(width 0.1524)
				(type default)
			)
			(layer "F.SilkS")
		)
		(fp_line
			(start 0.7874 -0.4064)
			(end 0.7874 0.4064)
			(stroke
				(width 0.1524)
				(type default)
			)
			(layer "F.SilkS")
		)
		(fp_line
			(start 0.7874 0.4064)
			(end -0.7874 0.4064)
			(stroke
				(width 0.1524)
				(type default)
			)
			(layer "F.SilkS")
		)
		(fp_line
			(start -0.6858 -0.3048)
			(end -0.1016 -0.3048)
			(stroke
				(width 0.1)
				(type default)
			)
			(layer "F.Fab")
		)
		(fp_line
			(start -0.6858 0.3048)
			(end -0.6858 -0.3048)
			(stroke
				(width 0.1)
				(type default)
			)
			(layer "F.Fab")
		)
		(fp_line
			(start -0.1016 -0.3048)
			(end -0.1016 -0.2794)
			(stroke
				(width 0.1)
				(type default)
			)
			(layer "F.Fab")
		)
		(fp_line
			(start -0.1016 -0.2794)
			(end 0.1016 -0.2794)
			(stroke
				(width 0.1)
				(type default)
			)
			(layer "F.Fab")
		)
		(fp_line
			(start -0.1016 0.2794)
			(end -0.1016 0.3048)
			(stroke
				(width 0.1)
				(type default)
			)
			(layer "F.Fab")
		)
		(fp_line
			(start -0.1016 0.3048)
			(end -0.6858 0.3048)
			(stroke
				(width 0.1)
				(type default)
			)
			(layer "F.Fab")
		)
		(fp_line
			(start 0.1016 -0.3048)
			(end 0.6858 -0.3048)
			(stroke
				(width 0.1)
				(type default)
			)
			(layer "F.Fab")
		)
		(fp_line
			(start 0.1016 -0.2794)
			(end 0.1016 -0.3048)
			(stroke
				(width 0.1)
				(type default)
			)
			(layer "F.Fab")
		)
		(fp_line
			(start 0.1016 0.2794)
			(end -0.1016 0.2794)
			(stroke
				(width 0.1)
				(type default)
			)
			(layer "F.Fab")
		)
		(fp_line
			(start 0.1016 0.3048)
			(end 0.1016 0.2794)
			(stroke
				(width 0.1)
				(type default)
			)
			(layer "F.Fab")
		)
		(fp_line
			(start 0.6858 -0.3048)
			(end 0.6858 0.3048)
			(stroke
				(width 0.1)
				(type default)
			)
			(layer "F.Fab")
		)
		(fp_line
			(start 0.6858 0.3048)
			(end 0.1016 0.3048)
			(stroke
				(width 0.1)
				(type default)
			)
			(layer "F.Fab")
		)
		(pad "1" smd rect
			(at -0.40005 0 180)
			(size 0.4572 0.508)
			(layers "F.Cu" "F.Mask" "F.Paste")
			(net "USB3_CPU0_BMC_HUB2_TX_DN")
		)
		(pad "2" smd rect
			(at 0.40005 0 180)
			(size 0.4572 0.508)
			(layers "F.Cu" "F.Mask" "F.Paste")
			(net "USB3_CPU0_BMC_TX_BUF_C_DN")
		)
	)
	(footprint ""
		(layer "F.Cu")
		(at 32.744918 -351.10547)
		(property "Reference" "PC622_3"
			(at 0 0 0)
			(layer "F.SilkS")
			(hide yes)
			(effects
				(font
					(size 1.27 1.27)
				)
			)
		)
		(property "Value" ""
			(at 0 0 0)
			(layer "F.Fab")
			(effects
				(font
					(size 1.27 1.27)
				)
			)
		)
		(duplicate_pad_numbers_are_jumpers no)
		(fp_line
			(start -0.7874 -0.4064)
			(end 0.7874 -0.4064)
			(stroke
				(width 0.1524)
				(type default)
			)
			(layer "F.SilkS")
		)
		(fp_line
			(start -0.7874 0.4064)
			(end -0.7874 -0.4064)
			(stroke
				(width 0.1524)
				(type default)
			)
			(layer "F.SilkS")
		)
		(fp_line
			(start 0.7874 -0.4064)
			(end 0.7874 0.4064)
			(stroke
				(width 0.1524)
				(type default)
			)
			(layer "F.SilkS")
		)
		(fp_line
			(start 0.7874 0.4064)
			(end -0.7874 0.4064)
			(stroke
				(width 0.1524)
				(type default)
			)
			(layer "F.SilkS")
		)
		(fp_line
			(start -0.67945 -0.305054)
			(end -0.12065 -0.305054)
			(stroke
				(width 0.1)
				(type default)
			)
			(layer "F.Fab")
		)
		(fp_line
			(start -0.67945 0.3048)
			(end -0.67945 -0.305054)
			(stroke
				(width 0.1)
				(type default)
			)
			(layer "F.Fab")
		)
		(fp_line
			(start -0.12065 -0.305054)
			(end -0.12065 -0.2794)
			(stroke
				(width 0.1)
				(type default)
			)
			(layer "F.Fab")
		)
		(fp_line
			(start -0.12065 -0.2794)
			(end 0.12065 -0.2794)
			(stroke
				(width 0.1)
				(type default)
			)
			(layer "F.Fab")
		)
		(fp_line
			(start -0.12065 0.2794)
			(end -0.12065 0.3048)
			(stroke
				(width 0.1)
				(type default)
			)
			(layer "F.Fab")
		)
		(fp_line
			(start -0.12065 0.3048)
			(end -0.67945 0.3048)
			(stroke
				(width 0.1)
				(type default)
			)
			(layer "F.Fab")
		)
		(fp_line
			(start 0.120396 0.2794)
			(end -0.12065 0.2794)
			(stroke
				(width 0.1)
				(type default)
			)
			(layer "F.Fab")
		)
		(fp_line
			(start 0.120396 0.3048)
			(end 0.120396 0.2794)
			(stroke
				(width 0.1)
				(type default)
			)
			(layer "F.Fab")
		)
		(fp_line
			(start 0.12065 -0.3048)
			(end 0.67945 -0.3048)
			(stroke
				(width 0.1)
				(type default)
			)
			(layer "F.Fab")
		)
		(fp_line
			(start 0.12065 -0.2794)
			(end 0.12065 -0.3048)
			(stroke
				(width 0.1)
				(type default)
			)
			(layer "F.Fab")
		)
		(fp_line
			(start 0.67945 -0.3048)
			(end 0.67945 0.3048)
			(stroke
				(width 0.1)
				(type default)
			)
			(layer "F.Fab")
		)
		(fp_line
			(start 0.67945 0.3048)
			(end 0.120396 0.3048)
			(stroke
				(width 0.1)
				(type default)
			)
			(layer "F.Fab")
		)
		(pad "1" smd circle
			(at -0.40005 0)
			(size 0 0)
			(layers "F.Cu" "F.Mask" "F.Paste")
			(net "SW_P12V_AUX_PVDDIO_P1_FLT")
		)
		(pad "2" smd circle
			(at 0.40005 0)
			(size 0 0)
			(layers "F.Cu" "F.Mask" "F.Paste")
			(net "GND")
		)
	)
	(footprint ""
		(layer "F.Cu")
		(at 396.509748 -16.100298 90)
		(property "Reference" "C1553"
			(at 0 0 90)
			(layer "F.SilkS")
			(hide yes)
			(effects
				(font
					(size 1.27 1.27)
				)
			)
		)
		(property "Value" ""
			(at 0 0 90)
			(layer "F.Fab")
			(effects
				(font
					(size 1.27 1.27)
				)
			)
		)
		(duplicate_pad_numbers_are_jumpers no)
		(fp_line
			(start 0.299974 -0.150114)
			(end 0.299974 0.150114)
			(stroke
				(width 0.1)
				(type default)
			)
			(layer "F.Fab")
		)
		(fp_line
			(start -0.299974 -0.150114)
			(end 0.299974 -0.150114)
			(stroke
				(width 0.1)
				(type default)
			)
			(layer "F.Fab")
		)
		(fp_line
			(start 0.299974 0.150114)
			(end -0.299974 0.150114)
			(stroke
				(width 0.1)
				(type default)
			)
			(layer "F.Fab")
		)
		(fp_line
			(start -0.299974 0.150114)
			(end -0.299974 -0.150114)
			(stroke
				(width 0.1)
				(type default)
			)
			(layer "F.Fab")
		)
		(pad "1" smd rect
			(at -0.2667 0 90)
			(size 0.3048 0.381)
			(layers "F.Cu" "F.Mask" "F.Paste")
			(net "P5E_CPU0_G3_TX_C_DP<13>")
		)
		(pad "2" smd rect
			(at 0.2667 0 90)
			(size 0.3048 0.381)
			(layers "F.Cu" "F.Mask" "F.Paste")
			(net "P5E_CPU0_G3_TX_DP<13>")
		)
	)
)
